FILE_TYPE = CONNECTIVITY;
{Allegro Design Entry HDL 17.2-2016 S081 (4005846) 1/11/2022}
"PAGE_NUMBER" = 30;
0"NC";
1"P3V3_AUX\g";
2"P3V3_AUX\g";
3"P3V3_AUX\g";
4"P3V3_AUX\g";
5"P3V3_AUX\g";
6"P3V3_AUX\g";
7"P3V3_AUX\g";
8"P3V3_AUX\g";
9"P3V3_AUX\g";
10"P3V3_RGM\g";
11"P3V3_AUX\g";
12"GND\g";
13"GND\g";
14"GND\g";
15"GND\g";
16"GND\g";
17"GND\g";
18"GND\g";
19"GND\g";
20"GND\g";
21"UART_BMC_5_TXD_R";
22"UART_BMC_5_RXD_BUF1";
23"UART_BMC_5_RXD_R";
24"UART_BMC_5_TXD_BUF1_R";
25"UART_BMC_5_TXD_BUF_R";
26"UART_BMC_5_RXD_BUF1";
27"SPA_SOUT_SW_BUF_R";
28"UART_BMC_1_RXD_R";
29"UART_BIC_DBG_RX";
30"UART_BMC_5_RXD_BUF1_SW";
31"SPA_SIN_SW_BUF_R";
32"UART_BMC_5_TXD_BUF_R";
33"UART_BMC_5_RXD_BUF1";
34"UART_BMC_5_TXD_BUF1_R";
35"UART_BMC_5_RXD_BUF";
36"UART_BMC_5_RXD_BUF";
37"UART_BMC_5_RXD_BUF_R";
38"UART_BMC_5_TXD_BUF";
39"UART_BMC_5_TXD_BUF1";
40"UART_BMC_5_RXD_BUF1_R";
41"FM_UARTSW_MSB_N";
42"FM_UARTSW_LSB_N";
43"SPA_SOUT_SW_BUF";
44"SPA_SIN_SW_BUF";
45"FM_UARTSW_LSB_N";
46"FM_UARTSW_MSB_N";
47"UART_BIC_DBG_TX";
48"UART_BMC_5_TXD_BUF1_R";
49"UART_BMC_1_TXD_R";
%"UNIVERSAL_GND"
"1","(4025,3800)","0","logical_power","I117";
;
CDS_LIB"logical_power"
HDL_POWER"GND";
"A"15;
%"Q_RES"
"2","(1825,2450)","2","pure_quanta","I146";
;
PART_NUMBER"CS24702FB06"
MATERIAL"CHIP"
WATTAGE"1/16W"
TOLERANCE"1%"
VALUE"4.7K"
PACK_TYPE"0402LF"
SEC_TYPE"0402LF"
CDS_LIB"pure_quanta"
LOCATION"R67"
SEC"1";
"A"
$PN"1"2;
"B"
$PN"2"24;
%"Q_RES"
"1","(3250,850)","0","pure_quanta","I147";
;
TOLERANCE"1%"
PACK_TYPE"0402LF"
VALUE"33.2"
MATERIAL"CHIP"
WATTAGE"1/16W"
PART_NUMBER"CS03322FB03"
SEC_TYPE"0402LF"
CDS_LIB"pure_quanta"
LOCATION"R104"
SEC"1";
"B"
$PN"2"33;
"A"
$PN"1"37;
%"Q_RES"
"1","(3250,950)","0","pure_quanta","I148";
;
PACK_TYPE"0402LF"
VALUE"33.2"
MATERIAL"CHIP"
WATTAGE"1/16W"
TOLERANCE"1%"
PART_NUMBER"CS03322FB03"
SEC_TYPE"0402LF"
CDS_LIB"pure_quanta"
LOCATION"R102"
SEC"1";
"B"
$PN"2"32;
"A"
$PN"1"38;
%"Q_CAP"
"1","(2050,1300)","0","pure_quanta","I151";
;
MATERIAL"X7R"
VALUE"0.1UF"
TOLERANCE"10%"
VOLTAGE"25V"
PACK_TYPE"0402"
PART_NUMBER"CH4104K1B00"
CDS_LIB"pure_quanta"
LOCATION"C175"
$SEC"1"
CDS_SEC"1";
"B"
$PN"2"20;
"A"
$PN"1"8;
%"UNIVERSAL_GND"
"1","(2050,1075)","0","logical_power","I152";
;
HDL_POWER"GND"
CDS_LIB"logical_power";
"A"20;
%"UNIVERSAL_GND"
"1","(975,600)","0","logical_power","I154";
;
HDL_POWER"GND"
CDS_LIB"logical_power";
"A"19;
%"UNIVERSAL_GND"
"1","(-1850,600)","0","logical_power","I182";
;
HDL_POWER"GND"
CDS_LIB"logical_power";
"A"18;
%"SCONN3_21291035BR2"
"1","(-2225,925)","2","pure_quanta","I184";
;
PART_NUMBER"DFHD03MS251"
VALUE"SCONN3_212-91-035BR2"
PART_TYPE"SMLF"
MATERIAL"EMPTY"
CDS_LMAN_SYM_OUTLINE"-50,100,50,-100"
NEEDS_NO_SIZE"TRUE"
CDS_LIB"pure_quanta"
SEC_TYPE""
LOCATION"J6"
SEC"1";
"1"
$PN"1"25;
"2"
$PN"2"18;
"3"
$PN"3"36;
%"Q_RES"
"2","(1525,3700)","2","pure_quanta","I192";
;
PACK_TYPE"0402LF"
MATERIAL"EMPTY"
WATTAGE"1/16W"
PART_NUMBER"CS24702FB06"
VALUE"4.7K"
TOLERANCE"1%"
SEC_TYPE"0402LF"
CDS_LIB"pure_quanta"
LOCATION"R737"
SEC"1";
"A"
$PN"1"1;
"B"
$PN"2"44;
%"Q_RES"
"2","(1675,4725)","2","pure_quanta","I195";
;
MATERIAL"EMPTY"
PACK_TYPE"0402LF"
PART_NUMBER"CS24702FB06"
VALUE"4.7K"
TOLERANCE"1%"
WATTAGE"1/16W"
SEC_TYPE"0402LF"
CDS_LIB"pure_quanta"
LOCATION"R742"
SEC"1";
"A"
$PN"1"5;
"B"
$PN"2"43;
%"Q_RES"
"2","(850,1275)","2","pure_quanta","I197";
;
MATERIAL"CHIP"
WATTAGE"1/16W"
TOLERANCE"1%"
PACK_TYPE"0402LF"
PART_NUMBER"CS24702FB06"
VALUE"4.7K"
CDS_LIB"pure_quanta"
SEC_TYPE"0402LF"
LOCATION"R741"
SEC"1";
"A"
$PN"1"6;
"B"
$PN"2"35;
%"UNIVERSAL_POWER"
"1","(1825,2725)","0","logical_power","I207";
;
HDL_POWER"P3V3_AUX"
CDS_LIB"logical_power";
"A"2;
%"UNIVERSAL_POWER"
"1","(850,1525)","0","logical_power","I208";
;
HDL_POWER"P3V3_AUX"
CDS_LIB"logical_power";
"A"6;
%"UNIVERSAL_POWER"
"1","(1850,1575)","0","logical_power","I211";
;
HDL_POWER"P3V3_AUX"
CDS_LIB"logical_power";
"A"8;
%"UNIVERSAL_POWER"
"1","(1525,4000)","0","logical_power","I214";
;
HDL_POWER"P3V3_AUX"
CDS_LIB"logical_power";
"A"1;
%"UNIVERSAL_POWER"
"1","(1675,4925)","0","logical_power","I217";
;
HDL_POWER"P3V3_AUX"
CDS_LIB"logical_power";
"A"5;
%"Q_RES"
"2","(2200,2375)","2","pure_quanta","I221";
;
PACK_TYPE"0402LF"
VALUE"4.7K"
MATERIAL"CHIP"
PART_NUMBER"CS24702FB06"
WATTAGE"1/16W"
TOLERANCE"1%"
SEC_TYPE"0402LF"
CDS_LIB"pure_quanta"
LOCATION"R758"
SEC"1";
"A"
$PN"1"10;
"B"
$PN"2"23;
%"Q_RES"
"1","(1275,2150)","0","pure_quanta","I225";
;
PACK_TYPE"0402LF"
TOLERANCE"1%"
WATTAGE"1/16W"
MATERIAL"CHIP"
VALUE"33.2"
PART_NUMBER"CS03322FB03"
SEC_TYPE"0402LF"
CDS_LIB"pure_quanta"
LOCATION"R715"
SEC"1";
"B"
$PN"2"24;
"A"
$PN"1"39;
%"Q_RES"
"1","(1275,2050)","0","pure_quanta","I226";
;
MATERIAL"CHIP"
VALUE"33.2"
PACK_TYPE"0402LF"
TOLERANCE"1%"
WATTAGE"1/16W"
PART_NUMBER"CS03322FB03"
SEC_TYPE"0402LF"
CDS_LIB"pure_quanta"
LOCATION"R757"
SEC"1";
"B"
$PN"2"23;
"A"
$PN"1"40;
%"UNIVERSAL_POWER"
"1","(175,2775)","0","logical_power","I227";
;
HDL_POWER"P3V3_AUX"
CDS_LIB"logical_power";
"A"4;
%"UNIVERSAL_GND"
"1","(375,2275)","0","logical_power","I228";
;
HDL_POWER"GND"
CDS_LIB"logical_power";
"A"17;
%"Q_CAP"
"1","(375,2500)","0","pure_quanta","I229";
;
TOLERANCE"10%"
PART_NUMBER"CH4104K1B00"
VALUE"0.1UF"
VOLTAGE"25V"
MATERIAL"X7R"
PACK_TYPE"0402"
CDS_LIB"pure_quanta"
LOCATION"C268"
$SEC"1"
CDS_SEC"1";
"B"
$PN"2"17;
"A"
$PN"1"4;
%"UNIVERSAL_POWER"
"1","(-825,2725)","0","logical_power","I230";
;
HDL_POWER"P3V3_AUX"
CDS_LIB"logical_power";
"A"11;
%"Q_RES"
"2","(-825,2475)","2","pure_quanta","I231";
;
PACK_TYPE"0402LF"
VALUE"4.7K"
WATTAGE"1/16W"
TOLERANCE"1%"
PART_NUMBER"CS24702FB06"
MATERIAL"CHIP"
SEC_TYPE"0402LF"
CDS_LIB"pure_quanta"
LOCATION"R72"
SEC"1";
"A"
$PN"1"11;
"B"
$PN"2"22;
%"UNIVERSAL_GND"
"1","(-700,1800)","0","logical_power","I233";
;
HDL_POWER"GND"
CDS_LIB"logical_power";
"A"16;
%"UNIVERSAL_POWER"
"1","(2200,2650)","0","logical_power","I236";
;
HDL_POWER"P3V3_RGM"
CDS_LIB"logical_power";
"A"10;
%"Q_RES"
"1","(4900,2675)","0","pure_quanta","I237";
;
VALUE"33.2"
MATERIAL"CHIP"
WATTAGE"1/16W"
PACK_TYPE"0402LF"
TOLERANCE"1%"
CDS_LIB"pure_quanta"
SEC_TYPE"0402LF"
PART_NUMBER"CS03322FB03"
LOCATION"R766"
SEC"1";
"B"
$PN"2"30;
"A"
$PN"1"26;
%"UNIVERSAL_POWER"
"1","(3675,1525)","0","logical_power","I238";
;
HDL_POWER"P3V3_AUX"
CDS_LIB"logical_power";
"A"9;
%"Q_RES"
"2","(3675,1250)","2","pure_quanta","I239";
;
MATERIAL"CHIP"
PART_NUMBER"CS24702FB06"
PACK_TYPE"0402LF"
TOLERANCE"1%"
WATTAGE"1/16W"
VALUE"4.7K"
SEC_TYPE"0402LF"
CDS_LIB"pure_quanta"
LOCATION"R765"
SEC"1";
"A"
$PN"1"9;
"B"
$PN"2"32;
%"74LVC2G07DW7"
"1","(1425,900)","0","pure_quanta","I246";
;
PART_NUMBER"AL002G07003"
VALUE"74LVC2G07DW-7"
PART_TYPE"SMLF"
MATERIAL"IC"
NEEDS_NO_SIZE"TRUE"
CDS_LMAN_SYM_OUTLINE"-175,100,175,-100"
CDS_LIB"pure_quanta"
LOCATION"U24"
$SEC"1"
CDS_SEC"1";
"VCC"
$PN"5"8;
"GND"
$PN"2"19;
"2Y"
$PN"4"37;
"1Y"
$PN"6"38;
"2A"
$PN"3"35;
"1A"
$PN"1"34;
%"74LVC2G07DW7"
"1","(-250,2100)","0","pure_quanta","I247";
;
VALUE"74LVC2G07DW-7"
MATERIAL"IC"
PART_NUMBER"AL002G07003"
PART_TYPE"SMLF"
NEEDS_NO_SIZE"TRUE"
CDS_LMAN_SYM_OUTLINE"-175,100,175,-100"
CDS_LIB"pure_quanta"
LOCATION"U47"
$SEC"1"
CDS_SEC"1";
"VCC"
$PN"5"4;
"GND"
$PN"2"16;
"2Y"
$PN"4"40;
"1Y"
$PN"6"39;
"2A"
$PN"3"22;
"1A"
$PN"1"21;
%"FSA3357K8X"
"1","(3600,4100)","2","pure_quanta","I250";
;
MATERIAL"IC"
VALUE"FSA3357K8X"
PART_NUMBER"AL003357009"
PART_TYPE"SMLF"
CDS_LMAN_SYM_OUTLINE"-150,225,150,-225"
PIN_NAMES_ROTATE"True"
CDS_LIB"pure_quanta"
LOCATION"U2"
$SEC"1"
CDS_SEC"1";
"S1"
$PN"6"41;
"B0"
$PN"1"47;
"B1"
$PN"2"48;
"VCC"
$PN"8"7;
"S2"
$PN"5"42;
"B2"
$PN"3"49;
"GND"
$PN"4"15;
"A"
$PN"7"43;
%"FSA3357K8X"
"1","(3425,3125)","2","pure_quanta","I251";
;
MATERIAL"IC"
PART_TYPE"SMLF"
PART_NUMBER"AL003357009"
VALUE"FSA3357K8X"
CDS_LIB"pure_quanta"
PIN_NAMES_ROTATE"True"
CDS_LMAN_SYM_OUTLINE"-150,225,150,-225"
LOCATION"U3"
$SEC"1"
CDS_SEC"1";
"S1"
$PN"6"46;
"B0"
$PN"1"29;
"B1"
$PN"2"30;
"VCC"
$PN"8"3;
"S2"
$PN"5"45;
"B2"
$PN"3"28;
"GND"
$PN"4"14;
"A"
$PN"7"44;
%"UNIVERSAL_GND"
"1","(2825,3375)","0","logical_power","I253";
;
HDL_POWER"GND"
CDS_LIB"logical_power";
"A"13;
%"Q_CAP"
"1","(2825,3575)","0","pure_quanta","I254";
;
VOLTAGE"25V"
VALUE"0.1UF"
TOLERANCE"10%"
MATERIAL"X7R"
PACK_TYPE"0402"
PART_NUMBER"CH4104K1B00"
SEC_TYPE"0402"
CDS_LIB"pure_quanta"
LOCATION"C20"
SEC"1";
"B"
$PN"2"13;
"A"
$PN"1"3;
%"UNIVERSAL_POWER"
"1","(2650,3850)","0","logical_power","I255";
;
HDL_POWER"P3V3_AUX"
CDS_LIB"logical_power";
"A"3;
%"UNIVERSAL_GND"
"1","(3850,2825)","0","logical_power","I256";
;
HDL_POWER"GND"
CDS_LIB"logical_power";
"A"14;
%"UNIVERSAL_POWER"
"1","(2825,4825)","0","logical_power","I260";
;
HDL_POWER"P3V3_AUX"
CDS_LIB"logical_power";
"A"7;
%"Q_CAP"
"1","(3000,4550)","0","pure_quanta","I261";
;
PACK_TYPE"0402"
VALUE"0.1UF"
MATERIAL"X7R"
VOLTAGE"25V"
TOLERANCE"10%"
PART_NUMBER"CH4104K1B00"
CDS_LIB"pure_quanta"
SEC_TYPE"0402"
LOCATION"C19"
SEC"1";
"B"
$PN"2"12;
"A"
$PN"1"7;
%"UNIVERSAL_GND"
"1","(3000,4350)","0","logical_power","I262";
;
CDS_LIB"logical_power"
HDL_POWER"GND";
"A"12;
%"Q_RES"
"1","(350,3200)","0","pure_quanta","I266";
;
PACK_TYPE"0402LF"
VALUE"0"
PART_NUMBER"CS00002JB13"
MATERIAL"CHIP"
WATTAGE"1/16W"
TOLERANCE"5%"
CDS_LIB"pure_quanta"
LOCATION"R726"
$SEC"1"
CDS_SEC"1";
"B"
$PN"2"44;
"A"
$PN"1"31;
%"Q_RES"
"1","(475,4175)","0","pure_quanta","I267";
;
MATERIAL"CHIP"
PACK_TYPE"0402LF"
VALUE"0"
PART_NUMBER"CS00002JB13"
CDS_LIB"pure_quanta"
TOLERANCE"5%"
WATTAGE"1/16W"
LOCATION"R39"
$SEC"1"
CDS_SEC"1";
"B"
$PN"2"43;
"A"
$PN"1"27;
END.
